# S9S_MB_2U (Grand Teton) — schematic netlist excerpt (pin names and nets, part order shuffled) for the footprints in the layout excerpt that follows; sources: Cadence DE-HDL packaged netlist, KiCad conversion of 03242023_DA0F0TMBIJ0_F0T_Motherboard_J_brd_V01_OCP.brd

PR1773  Q_RES  3.3 1% CHIP  pkg 0402LF  page 270 : A = SW_PVCCIN_CPU0_BOOT7 ; B = SW_PVCCIN_CPU0_BOOT7_R
R3386  Q_RES  1K 1% CHIP  pkg 0402LF  page 167 : A = P3V3_AUX ; B = FM_P2E_BUF2_VOD_SEL

(kicad_pcb
	(version 20260206)
	(generator "pcbnew")
	(generator_version "10.0")
	(general
		(thickness 1.6)
		(legacy_teardrops no)
	)
	(paper "A4")
	(title_block
		(title "03242023_DA0F0TMBIJ0_F0T_Motherboard_J_brd_V01_OCP.brd")
		(comment 1 "Grand Teton / footprints 2486-2487 of 6105")
	)
	(layers
		(0 "F.Cu" signal "TOP")
		(4 "In1.Cu" signal "GND")
		(6 "In2.Cu" signal "IN1")
		(8 "In3.Cu" signal "GND1")
		(10 "In4.Cu" signal "IN2")
		(12 "In5.Cu" signal "GND2")
		(14 "In6.Cu" signal "IN3")
		(16 "In7.Cu" signal "GND3")
		(18 "In8.Cu" signal "VCC")
		(20 "In9.Cu" signal "VCC1")
		(22 "In10.Cu" signal "GND4")
		(24 "In11.Cu" signal "IN4")
		(26 "In12.Cu" signal "GND5")
		(28 "In13.Cu" signal "IN5")
		(30 "In14.Cu" signal "GND6")
		(32 "In15.Cu" signal "IN6")
		(34 "In16.Cu" signal "GND7")
		(2 "B.Cu" signal "BOTTOM")
		(9 "F.Adhes" user "F.Adhesive")
		(11 "B.Adhes" user "B.Adhesive")
		(13 "F.Paste" user "Package Geometry/Pastemask Top")
		(15 "B.Paste" user "Package Geometry/Pastemask Bottom")
		(5 "F.SilkS" user "Ref Des/Silkscreen Top")
		(7 "B.SilkS" user "Ref Des/Silkscreen Bottom")
		(1 "F.Mask" user "Board Geometry/Soldermask Top")
		(3 "B.Mask" user "Board Geometry/Soldermask Bottom")
		(17 "Dwgs.User" user "User.Drawings")
		(19 "Cmts.User" user "User.Comments")
		(21 "Eco1.User" user "User.Eco1")
		(23 "Eco2.User" user "User.Eco2")
		(25 "Edge.Cuts" user "Board Geometry/Outline")
		(27 "Margin" user)
		(31 "F.CrtYd" user "Package Geometry/Place Bound Top")
		(29 "B.CrtYd" user "Package Geometry/Place Bound Bottom")
		(35 "F.Fab" user "Ref Des/Assembly Top")
		(33 "B.Fab" user "Ref Des/Assembly Bottom")
	)
	(footprint ""
		(layer "F.Cu")
		(at 29.93009 -391.65149)
		(property "Reference" "R3386"
			(at 0 0 0)
			(layer "F.SilkS")
			(hide yes)
			(effects
				(font
					(size 1.27 1.27)
				)
			)
		)
		(property "Value" ""
			(at 0 0 0)
			(layer "F.Fab")
			(effects
				(font
					(size 1.27 1.27)
				)
			)
		)
		(duplicate_pad_numbers_are_jumpers no)
		(fp_line
			(start -0.7874 -0.4064)
			(end 0.7874 -0.4064)
			(stroke
				(width 0.1524)
				(type default)
			)
			(layer "F.SilkS")
		)
		(fp_line
			(start -0.7874 0.4064)
			(end -0.7874 -0.4064)
			(stroke
				(width 0.1524)
				(type default)
			)
			(layer "F.SilkS")
		)
		(fp_line
			(start 0.7874 -0.4064)
			(end 0.7874 0.4064)
			(stroke
				(width 0.1524)
				(type default)
			)
			(layer "F.SilkS")
		)
		(fp_line
			(start 0.7874 0.4064)
			(end -0.7874 0.4064)
			(stroke
				(width 0.1524)
				(type default)
			)
			(layer "F.SilkS")
		)
		(fp_line
			(start -0.67945 -0.305054)
			(end -0.12065 -0.305054)
			(stroke
				(width 0.1)
				(type default)
			)
			(layer "F.Fab")
		)
		(fp_line
			(start -0.67945 0.3048)
			(end -0.67945 -0.305054)
			(stroke
				(width 0.1)
				(type default)
			)
			(layer "F.Fab")
		)
		(fp_line
			(start -0.12065 -0.305054)
			(end -0.12065 -0.2794)
			(stroke
				(width 0.1)
				(type default)
			)
			(layer "F.Fab")
		)
		(fp_line
			(start -0.12065 -0.2794)
			(end 0.12065 -0.2794)
			(stroke
				(width 0.1)
				(type default)
			)
			(layer "F.Fab")
		)
		(fp_line
			(start -0.12065 0.2794)
			(end -0.12065 0.3048)
			(stroke
				(width 0.1)
				(type default)
			)
			(layer "F.Fab")
		)
		(fp_line
			(start -0.12065 0.3048)
			(end -0.67945 0.3048)
			(stroke
				(width 0.1)
				(type default)
			)
			(layer "F.Fab")
		)
		(fp_line
			(start 0.120396 0.2794)
			(end -0.12065 0.2794)
			(stroke
				(width 0.1)
				(type default)
			)
			(layer "F.Fab")
		)
		(fp_line
			(start 0.120396 0.3048)
			(end 0.120396 0.2794)
			(stroke
				(width 0.1)
				(type default)
			)
			(layer "F.Fab")
		)
		(fp_line
			(start 0.12065 -0.3048)
			(end 0.67945 -0.3048)
			(stroke
				(width 0.1)
				(type default)
			)
			(layer "F.Fab")
		)
		(fp_line
			(start 0.12065 -0.2794)
			(end 0.12065 -0.3048)
			(stroke
				(width 0.1)
				(type default)
			)
			(layer "F.Fab")
		)
		(fp_line
			(start 0.67945 -0.3048)
			(end 0.67945 0.3048)
			(stroke
				(width 0.1)
				(type default)
			)
			(layer "F.Fab")
		)
		(fp_line
			(start 0.67945 0.3048)
			(end 0.120396 0.3048)
			(stroke
				(width 0.1)
				(type default)
			)
			(layer "F.Fab")
		)
		(pad "1" smd circle
			(at -0.40005 0)
			(size 0 0)
			(layers "F.Cu" "F.Mask" "F.Paste")
			(net "P3V3_AUX")
		)
		(pad "2" smd circle
			(at 0.40005 0)
			(size 0 0)
			(layers "F.Cu" "F.Mask" "F.Paste")
			(net "FM_P2E_BUF2_VOD_SEL")
		)
	)
	(footprint ""
		(layer "F.Cu")
		(at 329.40625 -347.580458 90)
		(property "Reference" "PR1773"
			(at 0 0 90)
			(layer "F.SilkS")
			(hide yes)
			(effects
				(font
					(size 1.27 1.27)
				)
			)
		)
		(property "Value" ""
			(at 0 0 90)
			(layer "F.Fab")
			(effects
				(font
					(size 1.27 1.27)
				)
			)
		)
		(duplicate_pad_numbers_are_jumpers no)
		(fp_line
			(start 0.7874 -0.4064)
			(end 0.7874 0.4064)
			(stroke
				(width 0.1524)
				(type default)
			)
			(layer "F.SilkS")
		)
		(fp_line
			(start -0.7874 -0.4064)
			(end 0.7874 -0.4064)
			(stroke
				(width 0.1524)
				(type default)
			)
			(layer "F.SilkS")
		)
		(fp_line
			(start 0.7874 0.4064)
			(end -0.7874 0.4064)
			(stroke
				(width 0.1524)
				(type default)
			)
			(layer "F.SilkS")
		)
		(fp_line
			(start -0.7874 0.4064)
			(end -0.7874 -0.4064)
			(stroke
				(width 0.1524)
				(type default)
			)
			(layer "F.SilkS")
		)
		(fp_line
			(start -0.12065 -0.305054)
			(end -0.12065 -0.2794)
			(stroke
				(width 0.1)
				(type default)
			)
			(layer "F.Fab")
		)
		(fp_line
			(start -0.67945 -0.305054)
			(end -0.12065 -0.305054)
			(stroke
				(width 0.1)
				(type default)
			)
			(layer "F.Fab")
		)
		(fp_line
			(start 0.67945 -0.3048)
			(end 0.67945 0.3048)
			(stroke
				(width 0.1)
				(type default)
			)
			(layer "F.Fab")
		)
		(fp_line
			(start 0.12065 -0.3048)
			(end 0.67945 -0.3048)
			(stroke
				(width 0.1)
				(type default)
			)
			(layer "F.Fab")
		)
		(fp_line
			(start 0.12065 -0.2794)
			(end 0.12065 -0.3048)
			(stroke
				(width 0.1)
				(type default)
			)
			(layer "F.Fab")
		)
		(fp_line
			(start -0.12065 -0.2794)
			(end 0.12065 -0.2794)
			(stroke
				(width 0.1)
				(type default)
			)
			(layer "F.Fab")
		)
		(fp_line
			(start 0.120396 0.2794)
			(end -0.12065 0.2794)
			(stroke
				(width 0.1)
				(type default)
			)
			(layer "F.Fab")
		)
		(fp_line
			(start -0.12065 0.2794)
			(end -0.12065 0.3048)
			(stroke
				(width 0.1)
				(type default)
			)
			(layer "F.Fab")
		)
		(fp_line
			(start 0.67945 0.3048)
			(end 0.120396 0.3048)
			(stroke
				(width 0.1)
				(type default)
			)
			(layer "F.Fab")
		)
		(fp_line
			(start 0.120396 0.3048)
			(end 0.120396 0.2794)
			(stroke
				(width 0.1)
				(type default)
			)
			(layer "F.Fab")
		)
		(fp_line
			(start -0.12065 0.3048)
			(end -0.67945 0.3048)
			(stroke
				(width 0.1)
				(type default)
			)
			(layer "F.Fab")
		)
		(fp_line
			(start -0.67945 0.3048)
			(end -0.67945 -0.305054)
			(stroke
				(width 0.1)
				(type default)
			)
			(layer "F.Fab")
		)
		(pad "1" smd circle
			(at -0.40005 0 90)
			(size 0 0)
			(layers "F.Cu" "F.Mask" "F.Paste")
			(net "SW_PVCCIN_CPU0_BOOT7")
		)
		(pad "2" smd circle
			(at 0.40005 0 90)
			(size 0 0)
			(layers "F.Cu" "F.Mask" "F.Paste")
			(net "SW_PVCCIN_CPU0_BOOT7_R")
		)
	)
)
